(kicad_pcb
	(version 20260206)
	(generator "pcbnew")
	(generator_version "10.0")
	(general
		(thickness 1.6)
		(legacy_teardrops no)
	)
	(paper "A4")
	(title_block
		(title "Wiwynn_Tioga_Pass_MB.brd")
		(comment 1 "Tioga Pass / footprints 2726-2732 of 4770")
	)
	(layers
		(0 "F.Cu" signal "TOP")
		(4 "In1.Cu" signal "L2GND")
		(6 "In2.Cu" signal "L3")
		(8 "In3.Cu" signal "L4GND")
		(10 "In4.Cu" signal "L5")
		(12 "In5.Cu" signal "L6GND")
		(14 "In6.Cu" signal "L7VCC")
		(16 "In7.Cu" signal "L8VCC")
		(18 "In8.Cu" signal "L9GND")
		(20 "In9.Cu" signal "L10")
		(22 "In10.Cu" signal "L11GND")
		(24 "In11.Cu" signal "L12")
		(26 "In12.Cu" signal "L13GND")
		(2 "B.Cu" signal "BOTTOM")
		(9 "F.Adhes" user "F.Adhesive")
		(11 "B.Adhes" user "B.Adhesive")
		(13 "F.Paste" user "Package Geometry/Pastemask Top")
		(15 "B.Paste" user "Package Geometry/Pastemask Bottom")
		(5 "F.SilkS" user "Ref Des/Silkscreen Top")
		(7 "B.SilkS" user "Ref Des/Silkscreen Bottom")
		(1 "F.Mask" user "Board Geometry/Soldermask Top")
		(3 "B.Mask" user "Board Geometry/Soldermask Bottom")
		(17 "Dwgs.User" user "User.Drawings")
		(19 "Cmts.User" user "User.Comments")
		(21 "Eco1.User" user "User.Eco1")
		(23 "Eco2.User" user "User.Eco2")
		(25 "Edge.Cuts" user "Board Geometry/Outline")
		(27 "Margin" user)
		(31 "F.CrtYd" user "Package Geometry/Place Bound Top")
		(29 "B.CrtYd" user "Package Geometry/Place Bound Bottom")
		(35 "F.Fab" user "Ref Des/Assembly Top")
		(33 "B.Fab" user "Ref Des/Assembly Bottom")
	)
	(footprint ""
		(layer "B.Cu")
		(at 482.53015 -22.163024 -90)
		(property "Reference" "C1R23"
			(at -3.25247 1.2954 180)
			(unlocked yes)
			(layer "B.SilkS")
			(effects
				(font
					(size 0.7874 0.5842)
					(thickness 0.1524)
				)
				(justify mirror)
			)
		)
		(property "Value" ""
			(at 0 0 90)
			(layer "B.Fab")
			(effects
				(font
					(size 1.27 1.27)
				)
				(justify mirror)
			)
		)
		(duplicate_pad_numbers_are_jumpers no)
		(fp_line
			(start -2.286 7.366)
			(end -1.600708 7.366)
			(stroke
				(width 0.1524)
				(type default)
			)
			(layer "B.SilkS")
		)
		(fp_line
			(start -2.286 7.366)
			(end -2.286 1.63195)
			(stroke
				(width 0.1524)
				(type default)
			)
			(layer "B.SilkS")
		)
		(fp_line
			(start 2.286 7.366)
			(end 1.60147 7.366)
			(stroke
				(width 0.1524)
				(type default)
			)
			(layer "B.SilkS")
		)
		(fp_line
			(start 2.286 7.366)
			(end 2.286 1.632712)
			(stroke
				(width 0.1524)
				(type default)
			)
			(layer "B.SilkS")
		)
		(fp_line
			(start -2.504948 1.633728)
			(end -1.6002 1.633728)
			(stroke
				(width 0.1524)
				(type default)
			)
			(layer "B.SilkS")
		)
		(fp_line
			(start 2.563114 1.633728)
			(end 1.6002 1.633728)
			(stroke
				(width 0.1524)
				(type default)
			)
			(layer "B.SilkS")
		)
		(fp_line
			(start -2.504948 -1.616456)
			(end -2.504948 1.633728)
			(stroke
				(width 0.1524)
				(type default)
			)
			(layer "B.SilkS")
		)
		(fp_line
			(start -1.6002 -1.616456)
			(end -2.504948 -1.616456)
			(stroke
				(width 0.1524)
				(type default)
			)
			(layer "B.SilkS")
		)
		(fp_line
			(start 1.6002 -1.616456)
			(end 2.563114 -1.616456)
			(stroke
				(width 0.1524)
				(type default)
			)
			(layer "B.SilkS")
		)
		(fp_line
			(start 2.563114 -1.616456)
			(end 2.563114 1.633728)
			(stroke
				(width 0.1524)
				(type default)
			)
			(layer "B.SilkS")
		)
		(fp_line
			(start -2.286 7.366)
			(end 2.286 7.366)
			(stroke
				(width 0.1)
				(type default)
			)
			(layer "B.Fab")
		)
		(fp_line
			(start 2.286 7.366)
			(end 2.286 -0.254)
			(stroke
				(width 0.1)
				(type default)
			)
			(layer "B.Fab")
		)
		(fp_line
			(start -2.286 -0.254)
			(end -2.286 7.366)
			(stroke
				(width 0.1)
				(type default)
			)
			(layer "B.Fab")
		)
		(fp_line
			(start 2.286 -0.254)
			(end -2.286 -0.254)
			(stroke
				(width 0.1)
				(type default)
			)
			(layer "B.Fab")
		)
		(pad "1" smd rect
			(at 0 0 90)
			(size 2.54 3.048)
			(layers "B.Cu" "B.Mask" "B.Paste")
			(net "P12V_STBY")
		)
		(pad "2" smd rect
			(at 0 7.112 90)
			(size 2.54 3.048)
			(layers "B.Cu" "B.Mask" "B.Paste")
			(net "GND")
		)
	)
	(footprint ""
		(layer "B.Cu")
		(at 422.656 -153.035 90)
		(property "Reference" "C2L10"
			(at 0 0 90)
			(layer "B.SilkS")
			(hide yes)
			(effects
				(font
					(size 1.27 1.27)
				)
				(justify mirror)
			)
		)
		(property "Value" ""
			(at 0 0 90)
			(layer "B.Fab")
			(effects
				(font
					(size 1.27 1.27)
				)
				(justify mirror)
			)
		)
		(duplicate_pad_numbers_are_jumpers no)
		(fp_poly
			(pts
				(xy -0.3048 -0.1016) (xy -0.3048 0.9906) (xy 0.3048 0.9906) (xy 0.3048 -0.1016)
			)
			(stroke
				(width 0)
				(type default)
			)
			(fill no)
			(layer "B.CrtYd")
		)
		(fp_line
			(start 0.3048 -0.1016)
			(end 0.3048 0.9906)
			(stroke
				(width 0.1)
				(type default)
			)
			(layer "B.Fab")
		)
		(fp_line
			(start -0.3048 -0.1016)
			(end 0.3048 -0.1016)
			(stroke
				(width 0.1)
				(type default)
			)
			(layer "B.Fab")
		)
		(fp_line
			(start 0.3048 0.9906)
			(end -0.3048 0.9906)
			(stroke
				(width 0.1)
				(type default)
			)
			(layer "B.Fab")
		)
		(fp_line
			(start -0.3048 0.9906)
			(end -0.3048 -0.1016)
			(stroke
				(width 0.1)
				(type default)
			)
			(layer "B.Fab")
		)
		(pad "1" smd rect
			(at 0 0 270)
			(size 0.508 0.508)
			(layers "B.Cu" "B.Mask" "B.Paste")
			(net "SATA6G_PCH_PCIE_UP_SATA_RXP<1>")
		)
		(pad "2" smd rect
			(at 0 0.889 270)
			(size 0.508 0.508)
			(layers "B.Cu" "B.Mask" "B.Paste")
			(net "SATA6G_P1_RX_C_DP")
		)
		(zone
			(layer "B.Cu")
			(hatch none 0.5)
			(connect_pads
				(clearance 0)
			)
			(min_thickness 0.25)
			(keepout
				(tracks allowed)
				(vias not_allowed)
				(pads allowed)
				(copperpour not_allowed)
				(footprints allowed)
			)
			(placement
				(enabled no)
				(sheetname "")
			)
			(fill
				(thermal_gap 0.5)
				(thermal_bridge_width 0.5)
				(island_removal_mode 0)
			)
			(polygon
				(pts
					(xy 422.91 -153.289) (xy 422.91 -152.781) (xy 423.291 -152.781) (xy 423.291 -153.289)
				)
			)
		)
		(zone
			(layer "B.Cu")
			(hatch none 0.5)
			(connect_pads
				(clearance 0)
			)
			(min_thickness 0.25)
			(keepout
				(tracks not_allowed)
				(vias allowed)
				(pads allowed)
				(copperpour not_allowed)
				(footprints allowed)
			)
			(placement
				(enabled no)
				(sheetname "")
			)
			(fill
				(thermal_gap 0.5)
				(thermal_bridge_width 0.5)
				(island_removal_mode 0)
			)
			(polygon
				(pts
					(xy 423.291 -153.289) (xy 423.291 -152.781) (xy 422.91 -152.781) (xy 422.91 -153.289)
				)
			)
		)
	)
	(footprint ""
		(layer "B.Cu")
		(at 32.832802 -76.229464 90)
		(property "Reference" "C9P9"
			(at 0 0 90)
			(layer "B.SilkS")
			(hide yes)
			(effects
				(font
					(size 1.27 1.27)
				)
				(justify mirror)
			)
		)
		(property "Value" ""
			(at 0 0 90)
			(layer "B.Fab")
			(effects
				(font
					(size 1.27 1.27)
				)
				(justify mirror)
			)
		)
		(duplicate_pad_numbers_are_jumpers no)
		(fp_poly
			(pts
				(xy 0.7239 -0.2159) (xy -0.7239 -0.2159) (xy -0.7239 1.9939) (xy 0.7239 1.9939)
			)
			(stroke
				(width 0)
				(type default)
			)
			(fill no)
			(layer "B.CrtYd")
		)
		(fp_line
			(start 0.7239 -0.2159)
			(end 0.7239 1.9939)
			(stroke
				(width 0.1)
				(type default)
			)
			(layer "B.Fab")
		)
		(fp_line
			(start -0.7239 -0.2159)
			(end 0.7239 -0.2159)
			(stroke
				(width 0.1)
				(type default)
			)
			(layer "B.Fab")
		)
		(fp_line
			(start 0.7239 1.9939)
			(end -0.7239 1.9939)
			(stroke
				(width 0.1)
				(type default)
			)
			(layer "B.Fab")
		)
		(fp_line
			(start -0.7239 1.9939)
			(end -0.7239 -0.2159)
			(stroke
				(width 0.1)
				(type default)
			)
			(layer "B.Fab")
		)
		(pad "1" smd rect
			(at 0 0 270)
			(size 1.27 1.016)
			(layers "B.Cu" "B.Mask" "B.Paste")
			(net "VR_FET_SW_P12V_STBY_PVCCIN_CPU1")
		)
		(pad "2" smd rect
			(at 0 1.778 270)
			(size 1.27 1.016)
			(layers "B.Cu" "B.Mask" "B.Paste")
			(net "GND")
		)
		(zone
			(layer "B.Cu")
			(hatch none 0.5)
			(connect_pads
				(clearance 0)
			)
			(min_thickness 0.25)
			(keepout
				(tracks not_allowed)
				(vias allowed)
				(pads allowed)
				(copperpour not_allowed)
				(footprints allowed)
			)
			(placement
				(enabled no)
				(sheetname "")
			)
			(fill
				(thermal_gap 0.5)
				(thermal_bridge_width 0.5)
				(island_removal_mode 0)
			)
			(polygon
				(pts
					(xy 33.340802 -76.864464) (xy 33.340802 -75.594464) (xy 34.102802 -75.594464) (xy 34.102802 -76.864464)
				)
			)
		)
	)
	(footprint ""
		(layer "B.Cu")
		(at 422.402 -141.9606)
		(property "Reference" "C2L43"
			(at 0 0 0)
			(layer "B.SilkS")
			(hide yes)
			(effects
				(font
					(size 1.27 1.27)
				)
				(justify mirror)
			)
		)
		(property "Value" ""
			(at 0 0 0)
			(layer "B.Fab")
			(effects
				(font
					(size 1.27 1.27)
				)
				(justify mirror)
			)
		)
		(duplicate_pad_numbers_are_jumpers no)
		(fp_poly
			(pts
				(xy -0.3048 -0.1016) (xy -0.3048 0.9906) (xy 0.3048 0.9906) (xy 0.3048 -0.1016)
			)
			(stroke
				(width 0)
				(type default)
			)
			(fill no)
			(layer "B.CrtYd")
		)
		(fp_line
			(start -0.3048 -0.1016)
			(end 0.3048 -0.1016)
			(stroke
				(width 0.1)
				(type default)
			)
			(layer "B.Fab")
		)
		(fp_line
			(start -0.3048 0.9906)
			(end -0.3048 -0.1016)
			(stroke
				(width 0.1)
				(type default)
			)
			(layer "B.Fab")
		)
		(fp_line
			(start 0.3048 -0.1016)
			(end 0.3048 0.9906)
			(stroke
				(width 0.1)
				(type default)
			)
			(layer "B.Fab")
		)
		(fp_line
			(start 0.3048 0.9906)
			(end -0.3048 0.9906)
			(stroke
				(width 0.1)
				(type default)
			)
			(layer "B.Fab")
		)
		(pad "1" smd rect
			(at 0 0 180)
			(size 0.508 0.508)
			(layers "B.Cu" "B.Mask" "B.Paste")
			(net "SATA6G_P1_TX_C_DP")
		)
		(pad "2" smd rect
			(at 0 0.889 180)
			(size 0.508 0.508)
			(layers "B.Cu" "B.Mask" "B.Paste")
			(net "SATA6G_PCH_PCIE_UP_SATA_TXP<1>")
		)
		(zone
			(layer "B.Cu")
			(hatch none 0.5)
			(connect_pads
				(clearance 0)
			)
			(min_thickness 0.25)
			(keepout
				(tracks allowed)
				(vias not_allowed)
				(pads allowed)
				(copperpour not_allowed)
				(footprints allowed)
			)
			(placement
				(enabled no)
				(sheetname "")
			)
			(fill
				(thermal_gap 0.5)
				(thermal_bridge_width 0.5)
				(island_removal_mode 0)
			)
			(polygon
				(pts
					(xy 422.656 -141.7066) (xy 422.148 -141.7066) (xy 422.148 -141.3256) (xy 422.656 -141.3256)
				)
			)
		)
		(zone
			(layer "B.Cu")
			(hatch none 0.5)
			(connect_pads
				(clearance 0)
			)
			(min_thickness 0.25)
			(keepout
				(tracks not_allowed)
				(vias allowed)
				(pads allowed)
				(copperpour not_allowed)
				(footprints allowed)
			)
			(placement
				(enabled no)
				(sheetname "")
			)
			(fill
				(thermal_gap 0.5)
				(thermal_bridge_width 0.5)
				(island_removal_mode 0)
			)
			(polygon
				(pts
					(xy 422.656 -141.3256) (xy 422.148 -141.3256) (xy 422.148 -141.7066) (xy 422.656 -141.7066)
				)
			)
		)
	)
	(footprint ""
		(layer "B.Cu")
		(at 396.376906 -156.115258 -90)
		(property "Reference" "R2L24"
			(at 0 0 90)
			(layer "B.SilkS")
			(hide yes)
			(effects
				(font
					(size 1.27 1.27)
				)
				(justify mirror)
			)
		)
		(property "Value" ""
			(at 0 0 90)
			(layer "B.Fab")
			(effects
				(font
					(size 1.27 1.27)
				)
				(justify mirror)
			)
		)
		(duplicate_pad_numbers_are_jumpers no)
		(fp_poly
			(pts
				(xy 0.2794 -0.1016) (xy -0.2794 -0.1016) (xy -0.2794 0.9906) (xy 0.2794 0.9906)
			)
			(stroke
				(width 0)
				(type default)
			)
			(fill no)
			(layer "B.CrtYd")
		)
		(fp_line
			(start -0.2794 0.9906)
			(end -0.2794 -0.1016)
			(stroke
				(width 0.1)
				(type default)
			)
			(layer "B.Fab")
		)
		(fp_line
			(start 0.2794 0.9906)
			(end -0.2794 0.9906)
			(stroke
				(width 0.1)
				(type default)
			)
			(layer "B.Fab")
		)
		(fp_line
			(start -0.2794 -0.1016)
			(end 0.2794 -0.1016)
			(stroke
				(width 0.1)
				(type default)
			)
			(layer "B.Fab")
		)
		(fp_line
			(start 0.2794 -0.1016)
			(end 0.2794 0.9906)
			(stroke
				(width 0.1)
				(type default)
			)
			(layer "B.Fab")
		)
		(pad "1" smd rect
			(at 0 0 90)
			(size 0.508 0.508)
			(layers "B.Cu" "B.Mask" "B.Paste")
			(net "P3V3_STBY")
		)
		(pad "2" smd rect
			(at 0 0.889 90)
			(size 0.508 0.508)
			(layers "B.Cu" "B.Mask" "B.Paste")
			(net "PU_VR_PVNN_PCH_FAULT1")
		)
		(zone
			(layer "B.Cu")
			(hatch none 0.5)
			(connect_pads
				(clearance 0)
			)
			(min_thickness 0.25)
			(keepout
				(tracks not_allowed)
				(vias allowed)
				(pads allowed)
				(copperpour not_allowed)
				(footprints allowed)
			)
			(placement
				(enabled no)
				(sheetname "")
			)
			(fill
				(thermal_gap 0.5)
				(thermal_bridge_width 0.5)
				(island_removal_mode 0)
			)
			(polygon
				(pts
					(xy 395.741906 -155.861258) (xy 395.741906 -156.369258) (xy 396.122906 -156.369258) (xy 396.122906 -155.861258)
				)
			)
		)
		(zone
			(layer "B.Cu")
			(hatch none 0.5)
			(connect_pads
				(clearance 0)
			)
			(min_thickness 0.25)
			(keepout
				(tracks allowed)
				(vias not_allowed)
				(pads allowed)
				(copperpour not_allowed)
				(footprints allowed)
			)
			(placement
				(enabled no)
				(sheetname "")
			)
			(fill
				(thermal_gap 0.5)
				(thermal_bridge_width 0.5)
				(island_removal_mode 0)
			)
			(polygon
				(pts
					(xy 396.122906 -155.861258) (xy 396.122906 -156.369258) (xy 395.741906 -156.369258) (xy 395.741906 -155.861258)
				)
			)
		)
	)
	(footprint ""
		(layer "B.Cu")
		(at 439.1025 -48.641 -90)
		(property "Reference" "R2W1"
			(at 0.8382 -0.67818 270)
			(unlocked yes)
			(layer "B.SilkS")
			(effects
				(font
					(size 0.4064 0.254)
					(thickness 0.1524)
				)
				(justify left mirror)
			)
		)
		(property "Value" ""
			(at 0 0 90)
			(layer "B.Fab")
			(effects
				(font
					(size 1.27 1.27)
				)
				(justify mirror)
			)
		)
		(duplicate_pad_numbers_are_jumpers no)
		(fp_poly
			(pts
				(xy 0.2794 -0.1016) (xy -0.2794 -0.1016) (xy -0.2794 0.9906) (xy 0.2794 0.9906)
			)
			(stroke
				(width 0)
				(type default)
			)
			(fill no)
			(layer "B.CrtYd")
		)
		(fp_line
			(start -0.2794 0.9906)
			(end -0.2794 -0.1016)
			(stroke
				(width 0.1)
				(type default)
			)
			(layer "B.Fab")
		)
		(fp_line
			(start 0.2794 0.9906)
			(end -0.2794 0.9906)
			(stroke
				(width 0.1)
				(type default)
			)
			(layer "B.Fab")
		)
		(fp_line
			(start -0.2794 -0.1016)
			(end 0.2794 -0.1016)
			(stroke
				(width 0.1)
				(type default)
			)
			(layer "B.Fab")
		)
		(fp_line
			(start 0.2794 -0.1016)
			(end 0.2794 0.9906)
			(stroke
				(width 0.1)
				(type default)
			)
			(layer "B.Fab")
		)
		(pad "1" smd rect
			(at 0 0 90)
			(size 0.508 0.508)
			(layers "B.Cu" "B.Mask" "B.Paste")
			(net "P3V3_STBY")
		)
		(pad "2" smd rect
			(at 0 0.889 90)
			(size 0.508 0.508)
			(layers "B.Cu" "B.Mask" "B.Paste")
			(net "FM_MEZZB_PRSNT1_N")
		)
		(zone
			(layer "B.Cu")
			(hatch none 0.5)
			(connect_pads
				(clearance 0)
			)
			(min_thickness 0.25)
			(keepout
				(tracks not_allowed)
				(vias allowed)
				(pads allowed)
				(copperpour not_allowed)
				(footprints allowed)
			)
			(placement
				(enabled no)
				(sheetname "")
			)
			(fill
				(thermal_gap 0.5)
				(thermal_bridge_width 0.5)
				(island_removal_mode 0)
			)
			(polygon
				(pts
					(xy 438.4675 -48.387) (xy 438.4675 -48.895) (xy 438.8485 -48.895) (xy 438.8485 -48.387)
				)
			)
		)
		(zone
			(layer "B.Cu")
			(hatch none 0.5)
			(connect_pads
				(clearance 0)
			)
			(min_thickness 0.25)
			(keepout
				(tracks allowed)
				(vias not_allowed)
				(pads allowed)
				(copperpour not_allowed)
				(footprints allowed)
			)
			(placement
				(enabled no)
				(sheetname "")
			)
			(fill
				(thermal_gap 0.5)
				(thermal_bridge_width 0.5)
				(island_removal_mode 0)
			)
			(polygon
				(pts
					(xy 438.8485 -48.387) (xy 438.8485 -48.895) (xy 438.4675 -48.895) (xy 438.4675 -48.387)
				)
			)
		)
	)
	(footprint ""
		(layer "B.Cu")
		(at 453.5678 -153.6446 180)
		(property "Reference" "R9A2"
			(at 0 0 0)
			(layer "B.SilkS")
			(hide yes)
			(effects
				(font
					(size 1.27 1.27)
				)
				(justify mirror)
			)
		)
		(property "Value" ""
			(at 0 0 0)
			(layer "B.Fab")
			(effects
				(font
					(size 1.27 1.27)
				)
				(justify mirror)
			)
		)
		(duplicate_pad_numbers_are_jumpers no)
		(fp_poly
			(pts
				(xy 0.2794 -0.1016) (xy -0.2794 -0.1016) (xy -0.2794 0.9906) (xy 0.2794 0.9906)
			)
			(stroke
				(width 0)
				(type default)
			)
			(fill no)
			(layer "B.CrtYd")
		)
		(fp_line
			(start 0.2794 0.9906)
			(end -0.2794 0.9906)
			(stroke
				(width 0.1)
				(type default)
			)
			(layer "B.Fab")
		)
		(fp_line
			(start 0.2794 -0.1016)
			(end 0.2794 0.9906)
			(stroke
				(width 0.1)
				(type default)
			)
			(layer "B.Fab")
		)
		(fp_line
			(start -0.2794 0.9906)
			(end -0.2794 -0.1016)
			(stroke
				(width 0.1)
				(type default)
			)
			(layer "B.Fab")
		)
		(fp_line
			(start -0.2794 -0.1016)
			(end 0.2794 -0.1016)
			(stroke
				(width 0.1)
				(type default)
			)
			(layer "B.Fab")
		)
		(pad "1" smd rect
			(at 0 0)
			(size 0.508 0.508)
			(layers "B.Cu" "B.Mask" "B.Paste")
			(net "XDP_PCH_CPU_TCK0")
		)
		(pad "2" smd rect
			(at 0 0.889)
			(size 0.508 0.508)
			(layers "B.Cu" "B.Mask" "B.Paste")
			(net "XDP_CPU_GTL_TCK_R2")
		)
		(zone
			(layer "B.Cu")
			(hatch none 0.5)
			(connect_pads
				(clearance 0)
			)
			(min_thickness 0.25)
			(keepout
				(tracks not_allowed)
				(vias allowed)
				(pads allowed)
				(copperpour not_allowed)
				(footprints allowed)
			)
			(placement
				(enabled no)
				(sheetname "")
			)
			(fill
				(thermal_gap 0.5)
				(thermal_bridge_width 0.5)
				(island_removal_mode 0)
			)
			(polygon
				(pts
					(xy 453.3138 -154.2796) (xy 453.8218 -154.2796) (xy 453.8218 -153.8986) (xy 453.3138 -153.8986)
				)
			)
		)
		(zone
			(layer "B.Cu")
			(hatch none 0.5)
			(connect_pads
				(clearance 0)
			)
			(min_thickness 0.25)
			(keepout
				(tracks allowed)
				(vias not_allowed)
				(pads allowed)
				(copperpour not_allowed)
				(footprints allowed)
			)
			(placement
				(enabled no)
				(sheetname "")
			)
			(fill
				(thermal_gap 0.5)
				(thermal_bridge_width 0.5)
				(island_removal_mode 0)
			)
			(polygon
				(pts
					(xy 453.3138 -153.8986) (xy 453.8218 -153.8986) (xy 453.8218 -154.2796) (xy 453.3138 -154.2796)
				)
			)
		)
	)
)
